# TIMECARD (Time Appliance Project (Time Card)) — schematic netlist excerpt (pin names and nets, part order shuffled) for the footprints in the layout excerpt that follows; sources: Cadence DE-HDL packaged netlist, KiCad conversion of R4006-B0001-02_R01.brd

C250  CAPACITOR  0.1UF 25V 10%  pkg SMC_0402R_H022  page 9 : \1\ = UNNAMED_3_RESISTOR_I151_2 ; \2\ = SG
C237  CAPACITOR  0.1UF 10V 10%  pkg SMC_0402R_H022  page 31 : \1\ = XP3R3V_FPGA ; \2\ = SG

(kicad_pcb
	(version 20260206)
	(generator "pcbnew")
	(generator_version "10.0")
	(general
		(thickness 1.6)
		(legacy_teardrops no)
	)
	(paper "A4")
	(title_block
		(title "timecard-production-celestica-r4006 — R4006-B0001-02_R01.brd")
		(comment 1 "Time Appliance Project (Time Card) / footprints 549-550 of 1113")
	)
	(layers
		(0 "F.Cu" signal "TOP")
		(4 "In1.Cu" signal "L02_GND1")
		(6 "In2.Cu" signal "L03_SIG1")
		(8 "In3.Cu" signal "L04_GND2")
		(10 "In4.Cu" signal "L05_VCC1")
		(12 "In5.Cu" signal "L06_VCC2")
		(14 "In6.Cu" signal "L07_GND3")
		(16 "In7.Cu" signal "L08_SIG2")
		(18 "In8.Cu" signal "L09_GND4")
		(2 "B.Cu" signal "BOTTOM")
		(9 "F.Adhes" user "F.Adhesive")
		(11 "B.Adhes" user "B.Adhesive")
		(13 "F.Paste" user "Package Geometry/Pastemask Top")
		(15 "B.Paste" user "Package Geometry/Pastemask Bottom")
		(5 "F.SilkS" user "Ref Des/Silkscreen Top")
		(7 "B.SilkS" user "Ref Des/Silkscreen Bottom")
		(1 "F.Mask" user "Board Geometry/Soldermask Top")
		(3 "B.Mask" user "Board Geometry/Soldermask Bottom")
		(17 "Dwgs.User" user "User.Drawings")
		(19 "Cmts.User" user "User.Comments")
		(21 "Eco1.User" user "User.Eco1")
		(23 "Eco2.User" user "User.Eco2")
		(25 "Edge.Cuts" user "Board Geometry/Outline")
		(27 "Margin" user)
		(31 "F.CrtYd" user "Package Geometry/Place Bound Top")
		(29 "B.CrtYd" user "Package Geometry/Place Bound Bottom")
		(35 "F.Fab" user "Ref Des/Assembly Top")
		(33 "B.Fab" user "Ref Des/Assembly Bottom")
	)
	(footprint ""
		(layer "F.Cu")
		(at 105.8164 -70.9168 180)
		(property "Reference" "C237"
			(at -0.381 -3.59537 0)
			(unlocked yes)
			(layer "F.SilkS")
			(effects
				(font
					(size 0.7874 0.5842)
					(thickness 0.1524)
				)
			)
		)
		(property "Value" "VAL*"
			(at 0.0762 2.067306 180)
			(unlocked yes)
			(layer "F.Fab")
			(hide yes)
			(effects
				(font
					(size 0.7874 0.5842)
					(thickness 0.1524)
				)
			)
		)
		(property "Device Type" "CAPACITOR-G105-0B104-CK,0.1UF,A"
			(at 0.0508 1.127506 180)
			(unlocked yes)
			(layer "F.Fab")
			(hide yes)
			(effects
				(font
					(size 0.7874 0.5842)
					(thickness 0.1524)
				)
			)
		)
		(property "User Part Number" "PARTNUM*"
			(at 0.1016 4.023106 180)
			(unlocked yes)
			(layer "Cmts.User")
			(hide yes)
			(effects
				(font
					(size 0.7874 0.5842)
					(thickness 0.1524)
				)
			)
		)
		(property "Tolerance" "TOL*"
			(at 0.0762 3.032506 180)
			(unlocked yes)
			(layer "Cmts.User")
			(hide yes)
			(effects
				(font
					(size 0.7874 0.5842)
					(thickness 0.1524)
				)
			)
		)
		(duplicate_pad_numbers_are_jumpers no)
		(fp_line
			(start 1.143 0.5588)
			(end 1.143 -0.5588)
			(stroke
				(width 0.1)
				(type default)
			)
			(layer "F.SilkS")
		)
		(fp_line
			(start 1.143 -0.5588)
			(end -1.143 -0.5588)
			(stroke
				(width 0.1)
				(type default)
			)
			(layer "F.SilkS")
		)
		(fp_line
			(start -1.143 0.5588)
			(end 1.143 0.5588)
			(stroke
				(width 0.1)
				(type default)
			)
			(layer "F.SilkS")
		)
		(fp_line
			(start -1.143 -0.5588)
			(end -1.143 0.5588)
			(stroke
				(width 0.1)
				(type default)
			)
			(layer "F.SilkS")
		)
		(fp_rect
			(start -1.143 0.5588)
			(end 1.143 -0.5588)
			(stroke
				(width 0)
				(type default)
			)
			(fill no)
			(layer "F.CrtYd")
		)
		(fp_line
			(start 0.508 0.3048)
			(end 0.508 -0.3048)
			(stroke
				(width 0.1)
				(type default)
			)
			(layer "F.Fab")
		)
		(fp_line
			(start 0.508 -0.3048)
			(end -0.508 -0.3048)
			(stroke
				(width 0.1)
				(type default)
			)
			(layer "F.Fab")
		)
		(fp_line
			(start -0.508 0.3048)
			(end 0.508 0.3048)
			(stroke
				(width 0.1)
				(type default)
			)
			(layer "F.Fab")
		)
		(fp_line
			(start -0.508 -0.3048)
			(end -0.508 0.3048)
			(stroke
				(width 0.1)
				(type default)
			)
			(layer "F.Fab")
		)
		(pad "1" smd rect
			(at -0.5334 0 180)
			(size 0.7112 0.6096)
			(layers "F.Cu" "F.Mask" "F.Paste")
			(net "XP3R3V_FPGA")
		)
		(pad "2" smd rect
			(at 0.5334 0 180)
			(size 0.7112 0.6096)
			(layers "F.Cu" "F.Mask" "F.Paste")
			(net "SG")
		)
		(zone
			(layer "F.Cu")
			(hatch none 0.5)
			(connect_pads
				(clearance 0)
			)
			(min_thickness 0.25)
			(keepout
				(tracks allowed)
				(vias not_allowed)
				(pads allowed)
				(copperpour not_allowed)
				(footprints allowed)
			)
			(placement
				(enabled no)
				(sheetname "")
			)
			(fill
				(thermal_gap 0.5)
				(thermal_bridge_width 0.5)
				(island_removal_mode 0)
			)
			(polygon
				(pts
					(xy 105.8926 -71.2216) (xy 105.7402 -71.2216) (xy 105.7402 -70.612) (xy 105.8926 -70.612)
				)
			)
		)
	)
	(footprint ""
		(layer "F.Cu")
		(at 94.107 -61.087 -90)
		(property "Reference" "C250"
			(at 2.794 0.08763 90)
			(unlocked yes)
			(layer "F.SilkS")
			(effects
				(font
					(size 0.7874 0.5842)
					(thickness 0.1524)
				)
			)
		)
		(property "Value" "VAL*"
			(at 0.0762 2.067306 270)
			(unlocked yes)
			(layer "F.Fab")
			(hide yes)
			(effects
				(font
					(size 0.7874 0.5842)
					(thickness 0.1524)
				)
			)
		)
		(property "Tolerance" "TOL*"
			(at 0.0762 3.032506 270)
			(unlocked yes)
			(layer "Cmts.User")
			(hide yes)
			(effects
				(font
					(size 0.7874 0.5842)
					(thickness 0.1524)
				)
			)
		)
		(property "User Part Number" "PARTNUM*"
			(at 0.1016 4.023106 270)
			(unlocked yes)
			(layer "Cmts.User")
			(hide yes)
			(effects
				(font
					(size 0.7874 0.5842)
					(thickness 0.1524)
				)
			)
		)
		(property "Device Type" "CAPACITOR-G105-0B104-EK,0.1UF,A"
			(at 0.0508 1.127506 270)
			(unlocked yes)
			(layer "F.Fab")
			(hide yes)
			(effects
				(font
					(size 0.7874 0.5842)
					(thickness 0.1524)
				)
			)
		)
		(duplicate_pad_numbers_are_jumpers no)
		(fp_line
			(start -1.143 0.5588)
			(end 1.143 0.5588)
			(stroke
				(width 0.1)
				(type default)
			)
			(layer "F.SilkS")
		)
		(fp_line
			(start 1.143 0.5588)
			(end 1.143 -0.5588)
			(stroke
				(width 0.1)
				(type default)
			)
			(layer "F.SilkS")
		)
		(fp_line
			(start -1.143 -0.5588)
			(end -1.143 0.5588)
			(stroke
				(width 0.1)
				(type default)
			)
			(layer "F.SilkS")
		)
		(fp_line
			(start 1.143 -0.5588)
			(end -1.143 -0.5588)
			(stroke
				(width 0.1)
				(type default)
			)
			(layer "F.SilkS")
		)
		(fp_poly
			(pts
				(xy -1.143 0.5588) (xy 1.143 0.5588) (xy 1.143 -0.5588) (xy -1.143 -0.5588)
			)
			(stroke
				(width 0)
				(type default)
			)
			(fill no)
			(layer "F.CrtYd")
		)
		(fp_line
			(start -0.508 0.3048)
			(end 0.508 0.3048)
			(stroke
				(width 0.1)
				(type default)
			)
			(layer "F.Fab")
		)
		(fp_line
			(start 0.508 0.3048)
			(end 0.508 -0.3048)
			(stroke
				(width 0.1)
				(type default)
			)
			(layer "F.Fab")
		)
		(fp_line
			(start -0.508 -0.3048)
			(end -0.508 0.3048)
			(stroke
				(width 0.1)
				(type default)
			)
			(layer "F.Fab")
		)
		(fp_line
			(start 0.508 -0.3048)
			(end -0.508 -0.3048)
			(stroke
				(width 0.1)
				(type default)
			)
			(layer "F.Fab")
		)
		(pad "1" smd rect
			(at -0.5334 0 270)
			(size 0.7112 0.6096)
			(layers "F.Cu" "F.Mask" "F.Paste")
			(net "UNNAMED_3_RESISTOR_I151_2")
		)
		(pad "2" smd rect
			(at 0.5334 0 270)
			(size 0.7112 0.6096)
			(layers "F.Cu" "F.Mask" "F.Paste")
			(net "SG")
		)
		(zone
			(layer "F.Cu")
			(hatch none 0.5)
			(connect_pads
				(clearance 0)
			)
			(min_thickness 0.25)
			(keepout
				(tracks not_allowed)
				(vias allowed)
				(pads allowed)
				(copperpour not_allowed)
				(footprints allowed)
			)
			(placement
				(enabled no)
				(sheetname "")
			)
			(fill
				(thermal_gap 0.5)
				(thermal_bridge_width 0.5)
				(island_removal_mode 0)
			)
			(polygon
				(pts
					(xy 93.8022 -61.1632) (xy 93.8022 -61.0108) (xy 94.4118 -61.0108) (xy 94.4118 -61.1632)
				)
			)
		)
		(zone
			(layer "F.Cu")
			(hatch none 0.5)
			(connect_pads
				(clearance 0)
			)
			(min_thickness 0.25)
			(keepout
				(tracks allowed)
				(vias not_allowed)
				(pads allowed)
				(copperpour not_allowed)
				(footprints allowed)
			)
			(placement
				(enabled no)
				(sheetname "")
			)
			(fill
				(thermal_gap 0.5)
				(thermal_bridge_width 0.5)
				(island_removal_mode 0)
			)
			(polygon
				(pts
					(xy 93.8022 -61.1632) (xy 93.8022 -61.0108) (xy 94.4118 -61.0108) (xy 94.4118 -61.1632)
				)
			)
		)
	)
)
